(kicad_pcb
	(version 20260206)
	(generator "pcbnew")
	(generator_version "10.0")
	(general
		(thickness 1.6)
		(legacy_teardrops no)
	)
	(paper "A4")
	(title_block
		(title "04192023_DAF0TMB3IC0_F0TG_MB_C_brd_V02_OCP.brd")
		(comment 1 "Grand Teton / footprints 6420-6425 of 8354")
	)
	(layers
		(0 "F.Cu" signal "TOP")
		(4 "In1.Cu" signal "GND")
		(6 "In2.Cu" signal "IN1")
		(8 "In3.Cu" signal "GND1")
		(10 "In4.Cu" signal "IN2")
		(12 "In5.Cu" signal "GND2")
		(14 "In6.Cu" signal "IN3")
		(16 "In7.Cu" signal "GND3")
		(18 "In8.Cu" signal "VCC")
		(20 "In9.Cu" signal "VCC1")
		(22 "In10.Cu" signal "GND4")
		(24 "In11.Cu" signal "IN4")
		(26 "In12.Cu" signal "GND5")
		(28 "In13.Cu" signal "IN5")
		(30 "In14.Cu" signal "GND6")
		(32 "In15.Cu" signal "IN6")
		(34 "In16.Cu" signal "GND7")
		(2 "B.Cu" signal "BOTTOM")
		(9 "F.Adhes" user "F.Adhesive")
		(11 "B.Adhes" user "B.Adhesive")
		(13 "F.Paste" user "Package Geometry/Pastemask Top")
		(15 "B.Paste" user "Package Geometry/Pastemask Bottom")
		(5 "F.SilkS" user "Ref Des/Silkscreen Top")
		(7 "B.SilkS" user "Ref Des/Silkscreen Bottom")
		(1 "F.Mask" user "Board Geometry/Soldermask Top")
		(3 "B.Mask" user "Board Geometry/Soldermask Bottom")
		(17 "Dwgs.User" user "User.Drawings")
		(19 "Cmts.User" user "User.Comments")
		(21 "Eco1.User" user "User.Eco1")
		(23 "Eco2.User" user "User.Eco2")
		(25 "Edge.Cuts" user "Board Geometry/Outline")
		(27 "Margin" user)
		(31 "F.CrtYd" user "Package Geometry/Place Bound Top")
		(29 "B.CrtYd" user "Package Geometry/Place Bound Bottom")
		(35 "F.Fab" user "Ref Des/Assembly Top")
		(33 "B.Fab" user "Ref Des/Assembly Bottom")
	)
	(footprint ""
		(layer "B.Cu")
		(at 352.787712 -343.87409 -90)
		(property "Reference" "PC116_6"
			(at 0 0 90)
			(layer "B.SilkS")
			(hide yes)
			(effects
				(font
					(size 1.27 1.27)
				)
				(justify mirror)
			)
		)
		(property "Value" ""
			(at 0 0 90)
			(layer "B.Fab")
			(effects
				(font
					(size 1.27 1.27)
				)
				(justify mirror)
			)
		)
		(duplicate_pad_numbers_are_jumpers no)
		(fp_line
			(start -1.524 0.762)
			(end 1.524 0.762)
			(stroke
				(width 0.1524)
				(type default)
			)
			(layer "B.SilkS")
		)
		(fp_line
			(start 1.524 0.762)
			(end 1.524 -0.762)
			(stroke
				(width 0.1524)
				(type default)
			)
			(layer "B.SilkS")
		)
		(fp_line
			(start -1.524 -0.762)
			(end -1.524 0.762)
			(stroke
				(width 0.1524)
				(type default)
			)
			(layer "B.SilkS")
		)
		(fp_line
			(start 1.524 -0.762)
			(end -1.524 -0.762)
			(stroke
				(width 0.1524)
				(type default)
			)
			(layer "B.SilkS")
		)
		(fp_line
			(start -1.1049 0.724916)
			(end -1.1049 -0.724916)
			(stroke
				(width 0.1)
				(type default)
			)
			(layer "B.Fab")
		)
		(fp_line
			(start 1.1049 0.724916)
			(end -1.1049 0.724916)
			(stroke
				(width 0.1)
				(type default)
			)
			(layer "B.Fab")
		)
		(fp_line
			(start -1.1049 -0.724916)
			(end 1.1049 -0.724916)
			(stroke
				(width 0.1)
				(type default)
			)
			(layer "B.Fab")
		)
		(fp_line
			(start 1.1049 -0.724916)
			(end 1.1049 0.724916)
			(stroke
				(width 0.1)
				(type default)
			)
			(layer "B.Fab")
		)
		(pad "1" smd rect
			(at 0.889 0 270)
			(size 1.016 1.27)
			(layers "B.Cu" "B.Mask" "B.Paste")
			(net "SW_P12V_AUX_PVDDCR_CPU1_P0_FLT")
		)
		(pad "2" smd rect
			(at -0.889 0 270)
			(size 1.016 1.27)
			(layers "B.Cu" "B.Mask" "B.Paste")
			(net "GND")
		)
	)
	(footprint ""
		(layer "B.Cu")
		(at 116.781834 -272.284952)
		(property "Reference" "C2369"
			(at 0 0 0)
			(layer "B.SilkS")
			(hide yes)
			(effects
				(font
					(size 1.27 1.27)
				)
				(justify mirror)
			)
		)
		(property "Value" ""
			(at 0 0 0)
			(layer "B.Fab")
			(effects
				(font
					(size 1.27 1.27)
				)
				(justify mirror)
			)
		)
		(duplicate_pad_numbers_are_jumpers no)
		(fp_line
			(start -0.7874 -0.4064)
			(end -0.7874 0.4064)
			(stroke
				(width 0.1524)
				(type default)
			)
			(layer "B.SilkS")
		)
		(fp_line
			(start -0.7874 0.4064)
			(end 0.7874 0.4064)
			(stroke
				(width 0.1524)
				(type default)
			)
			(layer "B.SilkS")
		)
		(fp_line
			(start 0.7874 -0.4064)
			(end -0.7874 -0.4064)
			(stroke
				(width 0.1524)
				(type default)
			)
			(layer "B.SilkS")
		)
		(fp_line
			(start 0.7874 0.4064)
			(end 0.7874 -0.4064)
			(stroke
				(width 0.1524)
				(type default)
			)
			(layer "B.SilkS")
		)
		(fp_line
			(start -0.67945 -0.3048)
			(end -0.67945 0.3048)
			(stroke
				(width 0.1)
				(type default)
			)
			(layer "B.Fab")
		)
		(fp_line
			(start -0.67945 0.3048)
			(end -0.120396 0.3048)
			(stroke
				(width 0.1)
				(type default)
			)
			(layer "B.Fab")
		)
		(fp_line
			(start -0.12065 -0.3048)
			(end -0.67945 -0.3048)
			(stroke
				(width 0.1)
				(type default)
			)
			(layer "B.Fab")
		)
		(fp_line
			(start -0.12065 -0.2794)
			(end -0.12065 -0.3048)
			(stroke
				(width 0.1)
				(type default)
			)
			(layer "B.Fab")
		)
		(fp_line
			(start -0.120396 0.2794)
			(end 0.12065 0.2794)
			(stroke
				(width 0.1)
				(type default)
			)
			(layer "B.Fab")
		)
		(fp_line
			(start -0.120396 0.3048)
			(end -0.120396 0.2794)
			(stroke
				(width 0.1)
				(type default)
			)
			(layer "B.Fab")
		)
		(fp_line
			(start 0.12065 -0.305054)
			(end 0.12065 -0.2794)
			(stroke
				(width 0.1)
				(type default)
			)
			(layer "B.Fab")
		)
		(fp_line
			(start 0.12065 -0.2794)
			(end -0.12065 -0.2794)
			(stroke
				(width 0.1)
				(type default)
			)
			(layer "B.Fab")
		)
		(fp_line
			(start 0.12065 0.2794)
			(end 0.12065 0.3048)
			(stroke
				(width 0.1)
				(type default)
			)
			(layer "B.Fab")
		)
		(fp_line
			(start 0.12065 0.3048)
			(end 0.67945 0.3048)
			(stroke
				(width 0.1)
				(type default)
			)
			(layer "B.Fab")
		)
		(fp_line
			(start 0.67945 -0.305054)
			(end 0.12065 -0.305054)
			(stroke
				(width 0.1)
				(type default)
			)
			(layer "B.Fab")
		)
		(fp_line
			(start 0.67945 0.3048)
			(end 0.67945 -0.305054)
			(stroke
				(width 0.1)
				(type default)
			)
			(layer "B.Fab")
		)
		(pad "1" smd circle
			(at 0.40005 0 180)
			(size 0 0)
			(layers "B.Cu" "B.Mask" "B.Paste")
			(net "PVDDCR_CPU1_P1")
		)
		(pad "2" smd circle
			(at -0.40005 0 180)
			(size 0 0)
			(layers "B.Cu" "B.Mask" "B.Paste")
			(net "GND")
		)
	)
	(footprint ""
		(layer "B.Cu")
		(at 427.526958 -342.007952 -90)
		(property "Reference" "PC224_1"
			(at 0 0 90)
			(layer "B.SilkS")
			(hide yes)
			(effects
				(font
					(size 1.27 1.27)
				)
				(justify mirror)
			)
		)
		(property "Value" ""
			(at 0 0 90)
			(layer "B.Fab")
			(effects
				(font
					(size 1.27 1.27)
				)
				(justify mirror)
			)
		)
		(duplicate_pad_numbers_are_jumpers no)
		(fp_line
			(start -1.524 0.762)
			(end 1.524 0.762)
			(stroke
				(width 0.1524)
				(type default)
			)
			(layer "B.SilkS")
		)
		(fp_line
			(start 1.524 0.762)
			(end 1.524 -0.762)
			(stroke
				(width 0.1524)
				(type default)
			)
			(layer "B.SilkS")
		)
		(fp_line
			(start -1.524 -0.762)
			(end -1.524 0.762)
			(stroke
				(width 0.1524)
				(type default)
			)
			(layer "B.SilkS")
		)
		(fp_line
			(start 1.524 -0.762)
			(end -1.524 -0.762)
			(stroke
				(width 0.1524)
				(type default)
			)
			(layer "B.SilkS")
		)
		(fp_line
			(start -1.1049 0.724916)
			(end -1.1049 -0.724916)
			(stroke
				(width 0.1)
				(type default)
			)
			(layer "B.Fab")
		)
		(fp_line
			(start 1.1049 0.724916)
			(end -1.1049 0.724916)
			(stroke
				(width 0.1)
				(type default)
			)
			(layer "B.Fab")
		)
		(fp_line
			(start -1.1049 -0.724916)
			(end 1.1049 -0.724916)
			(stroke
				(width 0.1)
				(type default)
			)
			(layer "B.Fab")
		)
		(fp_line
			(start 1.1049 -0.724916)
			(end 1.1049 0.724916)
			(stroke
				(width 0.1)
				(type default)
			)
			(layer "B.Fab")
		)
		(pad "1" smd rect
			(at 0.889 0 270)
			(size 1.016 1.27)
			(layers "B.Cu" "B.Mask" "B.Paste")
			(net "PVDD11_S3_P0")
		)
		(pad "2" smd rect
			(at -0.889 0 270)
			(size 1.016 1.27)
			(layers "B.Cu" "B.Mask" "B.Paste")
			(net "GND")
		)
	)
	(footprint ""
		(layer "B.Cu")
		(at 182.737252 -97.112836 90)
		(property "Reference" "R1533"
			(at 0 0 90)
			(layer "B.SilkS")
			(hide yes)
			(effects
				(font
					(size 1.27 1.27)
				)
				(justify mirror)
			)
		)
		(property "Value" ""
			(at 0 0 90)
			(layer "B.Fab")
			(effects
				(font
					(size 1.27 1.27)
				)
				(justify mirror)
			)
		)
		(duplicate_pad_numbers_are_jumpers no)
		(fp_line
			(start 0.7874 -0.4064)
			(end -0.7874 -0.4064)
			(stroke
				(width 0.1524)
				(type default)
			)
			(layer "B.SilkS")
		)
		(fp_line
			(start -0.7874 -0.4064)
			(end -0.7874 0.4064)
			(stroke
				(width 0.1524)
				(type default)
			)
			(layer "B.SilkS")
		)
		(fp_line
			(start 0.7874 0.4064)
			(end 0.7874 -0.4064)
			(stroke
				(width 0.1524)
				(type default)
			)
			(layer "B.SilkS")
		)
		(fp_line
			(start -0.7874 0.4064)
			(end 0.7874 0.4064)
			(stroke
				(width 0.1524)
				(type default)
			)
			(layer "B.SilkS")
		)
		(fp_line
			(start 0.67945 -0.305054)
			(end 0.12065 -0.305054)
			(stroke
				(width 0.1)
				(type default)
			)
			(layer "B.Fab")
		)
		(fp_line
			(start 0.12065 -0.305054)
			(end 0.12065 -0.2794)
			(stroke
				(width 0.1)
				(type default)
			)
			(layer "B.Fab")
		)
		(fp_line
			(start -0.12065 -0.3048)
			(end -0.67945 -0.3048)
			(stroke
				(width 0.1)
				(type default)
			)
			(layer "B.Fab")
		)
		(fp_line
			(start -0.67945 -0.3048)
			(end -0.67945 0.3048)
			(stroke
				(width 0.1)
				(type default)
			)
			(layer "B.Fab")
		)
		(fp_line
			(start 0.12065 -0.2794)
			(end -0.12065 -0.2794)
			(stroke
				(width 0.1)
				(type default)
			)
			(layer "B.Fab")
		)
		(fp_line
			(start -0.12065 -0.2794)
			(end -0.12065 -0.3048)
			(stroke
				(width 0.1)
				(type default)
			)
			(layer "B.Fab")
		)
		(fp_line
			(start 0.12065 0.2794)
			(end 0.12065 0.3048)
			(stroke
				(width 0.1)
				(type default)
			)
			(layer "B.Fab")
		)
		(fp_line
			(start -0.120396 0.2794)
			(end 0.12065 0.2794)
			(stroke
				(width 0.1)
				(type default)
			)
			(layer "B.Fab")
		)
		(fp_line
			(start 0.67945 0.3048)
			(end 0.67945 -0.305054)
			(stroke
				(width 0.1)
				(type default)
			)
			(layer "B.Fab")
		)
		(fp_line
			(start 0.12065 0.3048)
			(end 0.67945 0.3048)
			(stroke
				(width 0.1)
				(type default)
			)
			(layer "B.Fab")
		)
		(fp_line
			(start -0.120396 0.3048)
			(end -0.120396 0.2794)
			(stroke
				(width 0.1)
				(type default)
			)
			(layer "B.Fab")
		)
		(fp_line
			(start -0.67945 0.3048)
			(end -0.120396 0.3048)
			(stroke
				(width 0.1)
				(type default)
			)
			(layer "B.Fab")
		)
		(pad "1" smd circle
			(at 0.40005 0 270)
			(size 0 0)
			(layers "B.Cu" "B.Mask" "B.Paste")
			(net "CPU0_THERMTRIP_R_N")
		)
		(pad "2" smd circle
			(at -0.40005 0 270)
			(size 0 0)
			(layers "B.Cu" "B.Mask" "B.Paste")
			(net "CPU1_THERMTRIP_R_N")
		)
	)
	(footprint ""
		(layer "B.Cu")
		(at 389.462264 8.689848 180)
		(property "Reference" "J74"
			(at 4.491482 -1.033526 270)
			(unlocked yes)
			(layer "B.SilkS")
			(effects
				(font
					(size 0.7874 0.5842)
					(thickness 0.1524)
				)
				(justify left mirror)
			)
		)
		(property "Value" ""
			(at 0 0 0)
			(layer "B.Fab")
			(effects
				(font
					(size 1.27 1.27)
				)
				(justify mirror)
			)
		)
		(duplicate_pad_numbers_are_jumpers no)
		(fp_line
			(start 1.2192 2.06756)
			(end 1.2192 -2.06756)
			(stroke
				(width 0.1524)
				(type default)
			)
			(layer "B.SilkS")
		)
		(fp_line
			(start 1.2192 -2.06756)
			(end -1.2192 -2.06756)
			(stroke
				(width 0.1524)
				(type default)
			)
			(layer "B.SilkS")
		)
		(fp_line
			(start -1.2192 2.06756)
			(end 1.2192 2.06756)
			(stroke
				(width 0.1524)
				(type default)
			)
			(layer "B.SilkS")
		)
		(fp_line
			(start -1.2192 -2.06756)
			(end -1.2192 2.06756)
			(stroke
				(width 0.1524)
				(type default)
			)
			(layer "B.SilkS")
		)
		(pad "" np_thru_hole circle
			(at -3.4671 -1.27 90)
			(size 1.0414 1.0414)
			(drill 1.0414)
			(layers "*.Cu" "*.Mask")
			(clearance 0.381)
			(thermal_gap 0.381)
		)
		(pad "" np_thru_hole circle
			(at -3.4671 1.27 90)
			(size 1.0414 1.0414)
			(drill 1.0414)
			(layers "*.Cu" "*.Mask")
			(clearance 0.381)
			(thermal_gap 0.381)
		)
		(pad "" np_thru_hole circle
			(at 2.8829 -1.27 90)
			(size 1.0414 1.0414)
			(drill 1.0414)
			(layers "*.Cu" "*.Mask")
			(clearance 0.381)
			(thermal_gap 0.381)
		)
		(pad "" np_thru_hole circle
			(at 2.8829 1.27 90)
			(size 1.0414 1.0414)
			(drill 1.0414)
			(layers "*.Cu" "*.Mask")
			(clearance 0.381)
			(thermal_gap 0.381)
		)
		(pad "1" smd rect
			(at -0.8255 -0.249936 90)
			(size 0.3048 0.508)
			(layers "B.Cu" "B.Mask" "B.Paste")
			(net "DELTA_L_85_5INCH_IN4_DN")
		)
		(pad "2" smd rect
			(at -0.8255 0.249936 90)
			(size 0.3048 0.508)
			(layers "B.Cu" "B.Mask" "B.Paste")
			(net "DELTA_L_85_5INCH_IN4_DP")
		)
		(pad "3" smd circle
			(at 0 0)
			(size 0 0)
			(layers "B.Cu" "B.Mask" "B.Paste")
			(net "DELTA_L_GND_1")
		)
		(zone
			(layers "F.Cu" "B.Cu" "In1.Cu" "In2.Cu" "In3.Cu" "In4.Cu" "In5.Cu" "In6.Cu"
				"In7.Cu" "In8.Cu" "In9.Cu" "In10.Cu" "In11.Cu" "In12.Cu" "In13.Cu" "In14.Cu"
				"In15.Cu" "In16.Cu"
			)
			(hatch none 0.5)
			(connect_pads
				(clearance 0)
			)
			(min_thickness 0.25)
			(keepout
				(tracks not_allowed)
				(vias allowed)
				(pads allowed)
				(copperpour not_allowed)
				(footprints allowed)
			)
			(placement
				(enabled no)
				(sheetname "")
			)
			(fill
				(thermal_gap 0.5)
				(thermal_bridge_width 0.5)
				(island_removal_mode 0)
			)
			(polygon
				(pts
					(arc
						(start 387.506464 7.419848)
						(mid 385.652264 7.419848)
						(end 387.506464 7.419848)
					)
				)
			)
		)
		(zone
			(layers "F.Cu" "B.Cu" "In1.Cu" "In2.Cu" "In3.Cu" "In4.Cu" "In5.Cu" "In6.Cu"
				"In7.Cu" "In8.Cu" "In9.Cu" "In10.Cu" "In11.Cu" "In12.Cu" "In13.Cu" "In14.Cu"
				"In15.Cu" "In16.Cu"
			)
			(hatch none 0.5)
			(connect_pads
				(clearance 0)
			)
			(min_thickness 0.25)
			(keepout
				(tracks not_allowed)
				(vias allowed)
				(pads allowed)
				(copperpour not_allowed)
				(footprints allowed)
			)
			(placement
				(enabled no)
				(sheetname "")
			)
			(fill
				(thermal_gap 0.5)
				(thermal_bridge_width 0.5)
				(island_removal_mode 0)
			)
			(polygon
				(pts
					(arc
						(start 387.506464 9.959848)
						(mid 385.652264 9.959848)
						(end 387.506464 9.959848)
					)
				)
			)
		)
		(zone
			(layers "F.Cu" "B.Cu" "In1.Cu" "In2.Cu" "In3.Cu" "In4.Cu" "In5.Cu" "In6.Cu"
				"In7.Cu" "In8.Cu" "In9.Cu" "In10.Cu" "In11.Cu" "In12.Cu" "In13.Cu" "In14.Cu"
				"In15.Cu" "In16.Cu"
			)
			(hatch none 0.5)
			(connect_pads
				(clearance 0)
			)
			(min_thickness 0.25)
			(keepout
				(tracks not_allowed)
				(vias allowed)
				(pads allowed)
				(copperpour not_allowed)
				(footprints allowed)
			)
			(placement
				(enabled no)
				(sheetname "")
			)
			(fill
				(thermal_gap 0.5)
				(thermal_bridge_width 0.5)
				(island_removal_mode 0)
			)
			(polygon
				(pts
					(arc
						(start 393.856464 7.419848)
						(mid 392.002264 7.419848)
						(end 393.856464 7.419848)
					)
				)
			)
		)
		(zone
			(layers "F.Cu" "B.Cu" "In1.Cu" "In2.Cu" "In3.Cu" "In4.Cu" "In5.Cu" "In6.Cu"
				"In7.Cu" "In8.Cu" "In9.Cu" "In10.Cu" "In11.Cu" "In12.Cu" "In13.Cu" "In14.Cu"
				"In15.Cu" "In16.Cu"
			)
			(hatch none 0.5)
			(connect_pads
				(clearance 0)
			)
			(min_thickness 0.25)
			(keepout
				(tracks not_allowed)
				(vias allowed)
				(pads allowed)
				(copperpour not_allowed)
				(footprints allowed)
			)
			(placement
				(enabled no)
				(sheetname "")
			)
			(fill
				(thermal_gap 0.5)
				(thermal_bridge_width 0.5)
				(island_removal_mode 0)
			)
			(polygon
				(pts
					(arc
						(start 393.856464 9.959848)
						(mid 392.002264 9.959848)
						(end 393.856464 9.959848)
					)
				)
			)
		)
		(zone
			(layer "B.Cu")
			(hatch none 0.5)
			(connect_pads
				(clearance 0)
			)
			(min_thickness 0.25)
			(keepout
				(tracks not_allowed)
				(vias allowed)
				(pads allowed)
				(copperpour not_allowed)
				(footprints allowed)
			)
			(placement
				(enabled no)
				(sheetname "")
			)
			(fill
				(thermal_gap 0.5)
				(thermal_bridge_width 0.5)
				(island_removal_mode 0)
			)
			(polygon
				(pts
					(xy 390.579864 9.238488) (xy 390.579864 9.142984) (xy 389.982964 9.142984) (xy 389.982964 8.736584)
					(xy 390.579864 8.736584) (xy 390.579864 8.643112) (xy 389.982964 8.643112) (xy 389.982964 8.236712)
					(xy 390.579864 8.236712) (xy 390.579864 8.141208) (xy 389.881364 8.141208) (xy 389.881364 9.238488)
				)
			)
		)
	)
	(footprint ""
		(layer "B.Cu")
		(at 91.762834 -308.606952 90)
		(property "Reference" "PR236"
			(at 0 0 90)
			(layer "B.SilkS")
			(hide yes)
			(effects
				(font
					(size 1.27 1.27)
				)
				(justify mirror)
			)
		)
		(property "Value" ""
			(at 0 0 90)
			(layer "B.Fab")
			(effects
				(font
					(size 1.27 1.27)
				)
				(justify mirror)
			)
		)
		(duplicate_pad_numbers_are_jumpers no)
		(fp_line
			(start 0.7874 -0.4064)
			(end -0.7874 -0.4064)
			(stroke
				(width 0.1524)
				(type default)
			)
			(layer "B.SilkS")
		)
		(fp_line
			(start -0.7874 -0.4064)
			(end -0.7874 0.4064)
			(stroke
				(width 0.1524)
				(type default)
			)
			(layer "B.SilkS")
		)
		(fp_line
			(start 0.7874 0.4064)
			(end 0.7874 -0.4064)
			(stroke
				(width 0.1524)
				(type default)
			)
			(layer "B.SilkS")
		)
		(fp_line
			(start -0.7874 0.4064)
			(end 0.7874 0.4064)
			(stroke
				(width 0.1524)
				(type default)
			)
			(layer "B.SilkS")
		)
		(fp_line
			(start 0.67945 -0.305054)
			(end 0.12065 -0.305054)
			(stroke
				(width 0.1)
				(type default)
			)
			(layer "B.Fab")
		)
		(fp_line
			(start 0.12065 -0.305054)
			(end 0.12065 -0.2794)
			(stroke
				(width 0.1)
				(type default)
			)
			(layer "B.Fab")
		)
		(fp_line
			(start -0.12065 -0.3048)
			(end -0.67945 -0.3048)
			(stroke
				(width 0.1)
				(type default)
			)
			(layer "B.Fab")
		)
		(fp_line
			(start -0.67945 -0.3048)
			(end -0.67945 0.3048)
			(stroke
				(width 0.1)
				(type default)
			)
			(layer "B.Fab")
		)
		(fp_line
			(start 0.12065 -0.2794)
			(end -0.12065 -0.2794)
			(stroke
				(width 0.1)
				(type default)
			)
			(layer "B.Fab")
		)
		(fp_line
			(start -0.12065 -0.2794)
			(end -0.12065 -0.3048)
			(stroke
				(width 0.1)
				(type default)
			)
			(layer "B.Fab")
		)
		(fp_line
			(start 0.12065 0.2794)
			(end 0.12065 0.3048)
			(stroke
				(width 0.1)
				(type default)
			)
			(layer "B.Fab")
		)
		(fp_line
			(start -0.120396 0.2794)
			(end 0.12065 0.2794)
			(stroke
				(width 0.1)
				(type default)
			)
			(layer "B.Fab")
		)
		(fp_line
			(start 0.67945 0.3048)
			(end 0.67945 -0.305054)
			(stroke
				(width 0.1)
				(type default)
			)
			(layer "B.Fab")
		)
		(fp_line
			(start 0.12065 0.3048)
			(end 0.67945 0.3048)
			(stroke
				(width 0.1)
				(type default)
			)
			(layer "B.Fab")
		)
		(fp_line
			(start -0.120396 0.3048)
			(end -0.120396 0.2794)
			(stroke
				(width 0.1)
				(type default)
			)
			(layer "B.Fab")
		)
		(fp_line
			(start -0.67945 0.3048)
			(end -0.120396 0.3048)
			(stroke
				(width 0.1)
				(type default)
			)
			(layer "B.Fab")
		)
		(pad "1" smd circle
			(at 0.40005 0 270)
			(size 0 0)
			(layers "B.Cu" "B.Mask" "B.Paste")
			(net "SVID_PVDDCR_CPU1_P1_SVC_R")
		)
		(pad "2" smd circle
			(at -0.40005 0 270)
			(size 0 0)
			(layers "B.Cu" "B.Mask" "B.Paste")
			(net "SVID_PVDDCR_CPU1_P1_SVC")
		)
	)
)
